#ISCELL
  pure_quanta quanta_title_block_c *
  *
#ISCELL
  standard offpage *
  page150_i10
#ISCELL
  standard offpage *
  page150_i11
#ISCELL
  standard offpage *
  page150_i12
#ISCELL
  pure_quanta_power gnd *
  page150_i13
#CELL
  pure_quanta q_cap *
  page150_i14
#ISCELL
  pure_quanta_power universal_power *
  page150_i15
#ISCELL
  pure_quanta_power gnd *
  page150_i16
#ISCELL
  pure_quanta_power gnd *
  page150_i17
#ISCELL
  pure_quanta_power universal_power *
  page150_i18
#CELL
  pure_quanta q_cap *
  page150_i19
#ISCELL
  standard offpage *
  page150_i20
#ISCELL
  standard offpage *
  page150_i21
#ISCELL
  standard offpage *
  page150_i22
#ISCELL
  standard offpage *
  page150_i23
#CELL
  pure_quanta q_res *
  page150_i24
#CELL
  pure_quanta q_res *
  page150_i25
#CELL
  pure_quanta q_res *
  page150_i26
#CELL
  pure_quanta q_res *
  page150_i27
#CELL
  pure_quanta sn74avc4t774pwr *
  page150_i28
#ISCELL
  standard offpage *
  page150_i29
#ISCELL
  standard offpage *
  page150_i30
#ISCELL
  standard offpage *
  page150_i31
#ISCELL
  standard offpage *
  page150_i32
#CELL
  pure_quanta q_res *
  page150_i33
#CELL
  pure_quanta q_res *
  page150_i34
#CELL
  pure_quanta q_res *
  page150_i35
#CELL
  pure_quanta q_res *
  page150_i36
#ISCELL
  pure_quanta_power universal_power *
  page150_i37
#ISCELL
  pure_quanta_power universal_power *
  page150_i38
#ISCELL
  pure_quanta_power gnd *
  page150_i39
#CELL
  pure_quanta q_cap *
  page150_i40
#ISCELL
  pure_quanta_power gnd *
  page150_i41
#ISCELL
  pure_quanta_power gnd *
  page150_i42
#CELL
  pure_quanta q_cap *
  page150_i43
#CELL
  pure_quanta sn74avc2t245rswr *
  page150_i60
#ISCELL
  standard offpage *
  page150_i61
#ISCELL
  standard offpage *
  page150_i62
#ISCELL
  pure_quanta_power gnd *
  page150_i63
#ISCELL
  pure_quanta_power universal_power *
  page150_i64
#ISCELL
  pure_quanta_power gnd *
  page150_i65
#CELL
  pure_quanta q_cap *
  page150_i66
#ISCELL
  pure_quanta_power universal_power *
  page150_i67
#ISCELL
  pure_quanta_power gnd *
  page150_i68
#CELL
  pure_quanta q_cap *
  page150_i69
#ISCELL
  pure_quanta_power gnd *
  page150_i70
#CELL
  pure_quanta q_res *
  page150_i71
#ISCELL
  standard offpage *
  page150_i72
#ISCELL
  standard offpage *
  page150_i73
#ISCELL
  standard offpage *
  page150_i74
#ISCELL
  standard offpage *
  page150_i75
#CELL
  pure_quanta sn74avc4t774pwr *
  page150_i8
#ISCELL
  standard offpage *
  page150_i9
